(kicad_pcb
	(version 20241229)
	(generator "pcbnew")
	(generator_version "9.0")
	(general
		(thickness 1.63)
		(legacy_teardrops no)
	)
	(paper "A4")
	(title_block
		(title "CM4 Baseboard")
		(date "2026-01-05")
		(rev "1.1.1")
		(company "Antmicro Ltd")
		(comment 1 "www.antmicro.com")
		(comment 9 "footprints 261-266 of 506")
	)
	(layers
		(0 "F.Cu" signal)
		(4 "In1.Cu" power)
		(6 "In2.Cu" power)
		(8 "In3.Cu" signal)
		(10 "In4.Cu" signal)
		(2 "B.Cu" signal)
		(9 "F.Adhes" user "F.Adhesive")
		(11 "B.Adhes" user "B.Adhesive")
		(13 "F.Paste" user)
		(15 "B.Paste" user)
		(5 "F.SilkS" user "F.Silkscreen")
		(7 "B.SilkS" user "B.Silkscreen")
		(1 "F.Mask" user)
		(3 "B.Mask" user)
		(17 "Dwgs.User" user "User.Drawings")
		(19 "Cmts.User" user "User.Comments")
		(21 "Eco1.User" user "User.Eco1")
		(23 "Eco2.User" user "User.Eco2")
		(25 "Edge.Cuts" user)
		(27 "Margin" user)
		(31 "F.CrtYd" user "F.Courtyard")
		(29 "B.CrtYd" user "B.Courtyard")
		(35 "F.Fab" user)
		(33 "B.Fab" user)
	)
	(footprint "antmicro-footprints:R_0402_1005Metric"
		(layer "F.Cu")
		(at 120.3 154.6415 180)
		(descr "Resistor SMD 0402")
		(tags "resistor SMD 0402")
		(property "Reference" "R218"
			(at -4.3 -0.175 180)
			(layer "F.SilkS")
			(effects
				(font
					(size 0.7 0.7)
					(thickness 0.15)
				)
				(justify left bottom)
			)
		)
		(property "Value" "R_0R_0402"
			(at -1.011843 1.772047 180)
			(layer "F.Fab")
			(effects
				(font
					(size 0.7 0.7)
					(thickness 0.15)
				)
				(justify left bottom)
			)
		)
		(property "Datasheet" "https://industrial.panasonic.com/cdbs/www-data/pdf/RDA0000/AOA0000C301.pdf"
			(at 0 0 180)
			(layer "F.Fab")
			(hide yes)
			(effects
				(font
					(size 1.27 1.27)
					(thickness 0.15)
				)
			)
		)
		(property "Manufacturer" "Panasonic"
			(at 0 0 180)
			(unlocked yes)
			(layer "F.Fab")
			(hide yes)
			(effects
				(font
					(size 1 1)
					(thickness 0.15)
				)
			)
		)
		(property "MPN" "ERJ2GE0R00X"
			(at 0 0 180)
			(unlocked yes)
			(layer "F.Fab")
			(hide yes)
			(effects
				(font
					(size 1 1)
					(thickness 0.15)
				)
			)
		)
		(property "Val" "0R"
			(at 0 0 180)
			(unlocked yes)
			(layer "F.Fab")
			(hide yes)
			(effects
				(font
					(size 1 1)
					(thickness 0.15)
				)
			)
		)
		(property "License" "Apache-2.0"
			(at 0 0 180)
			(unlocked yes)
			(layer "F.Fab")
			(hide yes)
			(effects
				(font
					(size 1 1)
					(thickness 0.15)
				)
			)
		)
		(property "Author" "Antmicro"
			(at 0 0 180)
			(unlocked yes)
			(layer "F.Fab")
			(hide yes)
			(effects
				(font
					(size 1 1)
					(thickness 0.15)
				)
			)
		)
		(property "Tolerance" "~"
			(at 0 0 180)
			(unlocked yes)
			(layer "F.Fab")
			(hide yes)
			(effects
				(font
					(size 1 1)
					(thickness 0.15)
				)
			)
		)
		(property "Current" "1A"
			(at 0 0 180)
			(unlocked yes)
			(layer "F.Fab")
			(hide yes)
			(effects
				(font
					(size 1 1)
					(thickness 0.15)
				)
			)
		)
		(sheetname "/Compute module/")
		(sheetfile "compute-module.kicad_sch")
		(attr smd)
		(fp_rect
			(start -0.925 -0.47)
			(end 0.925 0.47)
			(stroke
				(width 0.05)
				(type default)
			)
			(fill no)
			(layer "F.CrtYd")
		)
		(fp_rect
			(start -0.5 -0.25)
			(end 0.5 0.25)
			(stroke
				(width 0.15)
				(type solid)
			)
			(fill no)
			(layer "F.Fab")
		)
		(fp_text user "License: Apache-2.0"
			(at -0.95 5.169 180)
			(layer "F.Fab")
			(effects
				(font
					(size 0.7 0.7)
					(thickness 0.15)
				)
				(justify left bottom)
			)
		)
		(fp_text user "${REFERENCE}"
			(at -0.95 3.168 180)
			(layer "F.Fab")
			(effects
				(font
					(size 0.7 0.7)
					(thickness 0.15)
				)
				(justify left bottom)
			)
		)
		(fp_text user "Author: Antmicro"
			(at -0.95 4.169 180)
			(layer "F.Fab")
			(effects
				(font
					(size 0.7 0.7)
					(thickness 0.15)
				)
				(justify left bottom)
			)
		)
		(pad "1" smd roundrect
			(at -0.48 0 180)
			(size 0.59 0.64)
			(layers "F.Cu" "F.Mask" "F.Paste")
			(roundrect_rratio 0.25)
			(net 167 "/Compute module/NVMe.RX1_P")
			(pintype "passive")
		)
		(pad "2" smd roundrect
			(at 0.48 0 180)
			(size 0.59 0.64)
			(layers "F.Cu" "F.Mask" "F.Paste")
			(roundrect_rratio 0.25)
			(net 147 "/Compute module/R1_P")
			(pintype "passive")
		)
	)
	(footprint "antmicro-footprints:R_0402_1005Metric"
		(layer "F.Cu")
		(at 117.88 155.8415 180)
		(descr "Resistor SMD 0402")
		(tags "resistor SMD 0402")
		(property "Reference" "R220"
			(at -3.5 -0.325 180)
			(layer "F.SilkS")
			(effects
				(font
					(size 0.7 0.7)
					(thickness 0.15)
				)
				(justify left bottom)
			)
		)
		(property "Value" "R_0R_0402"
			(at -1.011843 1.772047 180)
			(layer "F.Fab")
			(effects
				(font
					(size 0.7 0.7)
					(thickness 0.15)
				)
				(justify left bottom)
			)
		)
		(property "Datasheet" "https://industrial.panasonic.com/cdbs/www-data/pdf/RDA0000/AOA0000C301.pdf"
			(at 0 0 180)
			(layer "F.Fab")
			(hide yes)
			(effects
				(font
					(size 1.27 1.27)
					(thickness 0.15)
				)
			)
		)
		(property "Manufacturer" "Panasonic"
			(at 0 0 180)
			(unlocked yes)
			(layer "F.Fab")
			(hide yes)
			(effects
				(font
					(size 1 1)
					(thickness 0.15)
				)
			)
		)
		(property "MPN" "ERJ2GE0R00X"
			(at 0 0 180)
			(unlocked yes)
			(layer "F.Fab")
			(hide yes)
			(effects
				(font
					(size 1 1)
					(thickness 0.15)
				)
			)
		)
		(property "Val" "0R"
			(at 0 0 180)
			(unlocked yes)
			(layer "F.Fab")
			(hide yes)
			(effects
				(font
					(size 1 1)
					(thickness 0.15)
				)
			)
		)
		(property "License" "Apache-2.0"
			(at 0 0 180)
			(unlocked yes)
			(layer "F.Fab")
			(hide yes)
			(effects
				(font
					(size 1 1)
					(thickness 0.15)
				)
			)
		)
		(property "Author" "Antmicro"
			(at 0 0 180)
			(unlocked yes)
			(layer "F.Fab")
			(hide yes)
			(effects
				(font
					(size 1 1)
					(thickness 0.15)
				)
			)
		)
		(property "Tolerance" "~"
			(at 0 0 180)
			(unlocked yes)
			(layer "F.Fab")
			(hide yes)
			(effects
				(font
					(size 1 1)
					(thickness 0.15)
				)
			)
		)
		(property "Current" "1A"
			(at 0 0 180)
			(unlocked yes)
			(layer "F.Fab")
			(hide yes)
			(effects
				(font
					(size 1 1)
					(thickness 0.15)
				)
			)
		)
		(sheetname "/Compute module/")
		(sheetfile "compute-module.kicad_sch")
		(attr smd)
		(fp_rect
			(start -0.925 -0.47)
			(end 0.925 0.47)
			(stroke
				(width 0.05)
				(type default)
			)
			(fill no)
			(layer "F.CrtYd")
		)
		(fp_rect
			(start -0.5 -0.25)
			(end 0.5 0.25)
			(stroke
				(width 0.15)
				(type solid)
			)
			(fill no)
			(layer "F.Fab")
		)
		(fp_text user "Author: Antmicro"
			(at -0.95 4.169 180)
			(layer "F.Fab")
			(effects
				(font
					(size 0.7 0.7)
					(thickness 0.15)
				)
				(justify left bottom)
			)
		)
		(fp_text user "License: Apache-2.0"
			(at -0.95 5.169 180)
			(layer "F.Fab")
			(effects
				(font
					(size 0.7 0.7)
					(thickness 0.15)
				)
				(justify left bottom)
			)
		)
		(fp_text user "${REFERENCE}"
			(at -0.95 3.168 180)
			(layer "F.Fab")
			(effects
				(font
					(size 0.7 0.7)
					(thickness 0.15)
				)
				(justify left bottom)
			)
		)
		(pad "1" smd roundrect
			(at -0.48 0 180)
			(size 0.59 0.64)
			(layers "F.Cu" "F.Mask" "F.Paste")
			(roundrect_rratio 0.25)
			(net 165 "/Compute module/NVMe.TX2_P")
			(pintype "passive")
		)
		(pad "2" smd roundrect
			(at 0.48 0 180)
			(size 0.59 0.64)
			(layers "F.Cu" "F.Mask" "F.Paste")
			(roundrect_rratio 0.25)
			(net 150 "/Compute module/T2_P")
			(pintype "passive")
		)
	)
	(footprint "antmicro-footprints:C_0402_1005Metric"
		(layer "F.Cu")
		(at 83.542962 153.1415 -90)
		(descr "Capacitor SMD 0402")
		(tags "capacitor SMD 0402")
		(property "Reference" "C204"
			(at -0.865 0.475 90)
			(layer "F.SilkS")
			(effects
				(font
					(size 0.7 0.7)
					(thickness 0.15)
				)
				(justify right bottom)
			)
		)
		(property "Value" "C_100n_0402"
			(at -1.022927 2.155213 90)
			(layer "F.Fab")
			(effects
				(font
					(size 0.7 0.7)
					(thickness 0.15)
				)
				(justify right bottom)
			)
		)
		(property "Datasheet" "https://www.murata.com/products/productdetail?partno=GRM155R61H104KE14%23"
			(at 0 0 270)
			(layer "F.Fab")
			(hide yes)
			(effects
				(font
					(size 1.27 1.27)
					(thickness 0.15)
				)
			)
		)
		(property "MPN" "GRM155R61H104KE14D"
			(at 0 0 270)
			(unlocked yes)
			(layer "F.Fab")
			(hide yes)
			(effects
				(font
					(size 1 1)
					(thickness 0.15)
				)
			)
		)
		(property "Manufacturer" "Murata"
			(at 0 0 270)
			(unlocked yes)
			(layer "F.Fab")
			(hide yes)
			(effects
				(font
					(size 1 1)
					(thickness 0.15)
				)
			)
		)
		(property "License" "Apache-2.0"
			(at 0 0 270)
			(unlocked yes)
			(layer "F.Fab")
			(hide yes)
			(effects
				(font
					(size 1 1)
					(thickness 0.15)
				)
			)
		)
		(property "Author" "Antmicro"
			(at 0 0 270)
			(unlocked yes)
			(layer "F.Fab")
			(hide yes)
			(effects
				(font
					(size 1 1)
					(thickness 0.15)
				)
			)
		)
		(property "Val" "100n"
			(at 0 0 270)
			(unlocked yes)
			(layer "F.Fab")
			(hide yes)
			(effects
				(font
					(size 1 1)
					(thickness 0.15)
				)
			)
		)
		(property "Voltage" "50V"
			(at 0 0 270)
			(unlocked yes)
			(layer "F.Fab")
			(hide yes)
			(effects
				(font
					(size 1 1)
					(thickness 0.15)
				)
			)
		)
		(property "Dielectric" "X5R"
			(at 0 0 270)
			(unlocked yes)
			(layer "F.Fab")
			(hide yes)
			(effects
				(font
					(size 1 1)
					(thickness 0.15)
				)
			)
		)
		(sheetname "/Compute module/")
		(sheetfile "compute-module.kicad_sch")
		(attr smd)
		(fp_rect
			(start -0.925 -0.47)
			(end 0.925 0.47)
			(stroke
				(width 0.05)
				(type default)
			)
			(fill no)
			(layer "F.CrtYd")
		)
		(fp_line
			(start -0.494 0.248)
			(end -0.494 -0.25)
			(stroke
				(width 0.15)
				(type solid)
			)
			(layer "F.Fab")
		)
		(fp_line
			(start 0.504 0.248)
			(end -0.494 0.248)
			(stroke
				(width 0.15)
				(type solid)
			)
			(layer "F.Fab")
		)
		(fp_line
			(start -0.494 -0.25)
			(end 0.504 -0.25)
			(stroke
				(width 0.15)
				(type solid)
			)
			(layer "F.Fab")
		)
		(fp_line
			(start 0.504 -0.25)
			(end 0.504 0.248)
			(stroke
				(width 0.15)
				(type solid)
			)
			(layer "F.Fab")
		)
		(fp_text user "${REFERENCE}"
			(at -0.939 4.599 270)
			(layer "F.Fab")
			(effects
				(font
					(size 0.7 0.7)
					(thickness 0.15)
				)
				(justify left bottom)
			)
		)
		(fp_text user "Author: Antmicro"
			(at -0.939 3.399 270)
			(layer "F.Fab")
			(effects
				(font
					(size 0.7 0.7)
					(thickness 0.15)
				)
				(justify left bottom)
			)
		)
		(fp_text user "License: Apache-2.0"
			(at -0.939 5.799 270)
			(layer "F.Fab")
			(effects
				(font
					(size 0.7 0.7)
					(thickness 0.15)
				)
				(justify left bottom)
			)
		)
		(pad "1" smd roundrect
			(at -0.48 0 270)
			(size 0.59 0.64)
			(layers "F.Cu" "F.Mask" "F.Paste")
			(roundrect_rratio 0.25)
			(net 3 "GND")
			(pintype "passive")
		)
		(pad "2" smd roundrect
			(at 0.48 0 270)
			(size 0.59 0.64)
			(layers "F.Cu" "F.Mask" "F.Paste")
			(roundrect_rratio 0.25)
			(net 18 "V_{IO}")
			(pintype "passive")
		)
	)
	(footprint "antmicro-footprints:R_0402_1005Metric"
		(layer "F.Cu")
		(at 95.092962 133.807236 -90)
		(descr "Resistor SMD 0402")
		(tags "resistor SMD 0402")
		(property "Reference" "R922"
			(at -0.930736 -1.385 90)
			(layer "F.SilkS")
			(effects
				(font
					(size 0.7 0.7)
					(thickness 0.15)
				)
				(justify right bottom)
			)
		)
		(property "Value" "R_12k_0402"
			(at -1.011843 1.772047 90)
			(layer "F.Fab")
			(effects
				(font
					(size 0.7 0.7)
					(thickness 0.15)
				)
				(justify right bottom)
			)
		)
		(property "Datasheet" "https://www.bourns.com/docs/product-datasheets/cr.pdf"
			(at 0 0 270)
			(layer "F.Fab")
			(hide yes)
			(effects
				(font
					(size 1.27 1.27)
					(thickness 0.15)
				)
			)
		)
		(property "Manufacturer" "Bourns"
			(at 0 0 270)
			(unlocked yes)
			(layer "F.Fab")
			(hide yes)
			(effects
				(font
					(size 1 1)
					(thickness 0.15)
				)
			)
		)
		(property "MPN" "CR0402-FX-1202GLF"
			(at 0 0 270)
			(unlocked yes)
			(layer "F.Fab")
			(hide yes)
			(effects
				(font
					(size 1 1)
					(thickness 0.15)
				)
			)
		)
		(property "Val" "12k"
			(at 0 0 270)
			(unlocked yes)
			(layer "F.Fab")
			(hide yes)
			(effects
				(font
					(size 1 1)
					(thickness 0.15)
				)
			)
		)
		(property "License" "Apache-2.0"
			(at 0 0 270)
			(unlocked yes)
			(layer "F.Fab")
			(hide yes)
			(effects
				(font
					(size 1 1)
					(thickness 0.15)
				)
			)
		)
		(property "Author" "Antmicro"
			(at 0 0 270)
			(unlocked yes)
			(layer "F.Fab")
			(hide yes)
			(effects
				(font
					(size 1 1)
					(thickness 0.15)
				)
			)
		)
		(property "Tolerance" "1%"
			(at 0 0 270)
			(unlocked yes)
			(layer "F.Fab")
			(hide yes)
			(effects
				(font
					(size 1 1)
					(thickness 0.15)
				)
			)
		)
		(sheetname "/USB/")
		(sheetfile "usb.kicad_sch")
		(attr smd)
		(fp_rect
			(start -0.925 -0.47)
			(end 0.925 0.47)
			(stroke
				(width 0.05)
				(type default)
			)
			(fill no)
			(layer "F.CrtYd")
		)
		(fp_rect
			(start -0.5 -0.25)
			(end 0.5 0.25)
			(stroke
				(width 0.15)
				(type solid)
			)
			(fill no)
			(layer "F.Fab")
		)
		(fp_text user "License: Apache-2.0"
			(at -0.95 5.169 270)
			(layer "F.Fab")
			(effects
				(font
					(size 0.7 0.7)
					(thickness 0.15)
				)
				(justify left bottom)
			)
		)
		(fp_text user "${REFERENCE}"
			(at -0.95 3.168 270)
			(layer "F.Fab")
			(effects
				(font
					(size 0.7 0.7)
					(thickness 0.15)
				)
				(justify left bottom)
			)
		)
		(fp_text user "Author: Antmicro"
			(at -0.95 4.169 270)
			(layer "F.Fab")
			(effects
				(font
					(size 0.7 0.7)
					(thickness 0.15)
				)
				(justify left bottom)
			)
		)
		(pad "1" smd roundrect
			(at -0.48 0 270)
			(size 0.59 0.64)
			(layers "F.Cu" "F.Mask" "F.Paste")
			(roundrect_rratio 0.25)
			(net 3 "GND")
			(pintype "passive")
		)
		(pad "2" smd roundrect
			(at 0.48 0 270)
			(size 0.59 0.64)
			(layers "F.Cu" "F.Mask" "F.Paste")
			(roundrect_rratio 0.25)
			(net 378 "Net-(U905-REF)")
			(pintype "passive")
		)
	)
	(footprint "antmicro-footprints:TP_SMD_0.75mm"
		(layer "F.Cu")
		(at 96.917962 137.6665)
		(property "Reference" "TP905"
			(at 0.3 0.4 180)
			(layer "F.SilkS")
			(effects
				(font
					(size 0.7 0.7)
					(thickness 0.15)
				)
				(justify left bottom)
			)
		)
		(property "Value" "TP_0.75mm_SMD"
			(at 0 1.2 0)
			(layer "F.Fab")
			(effects
				(font
					(size 0.7 0.7)
					(thickness 0.15)
				)
				(justify left bottom)
			)
		)
		(property "MPN" ""
			(at 0 0 0)
			(unlocked yes)
			(layer "F.Fab")
			(hide yes)
			(effects
				(font
					(size 1 1)
					(thickness 0.15)
				)
			)
		)
		(property "Manufacturer" ""
			(at 0 0 0)
			(unlocked yes)
			(layer "F.Fab")
			(hide yes)
			(effects
				(font
					(size 1 1)
					(thickness 0.15)
				)
			)
		)
		(property "Author" "Antmicro"
			(at 0 0 0)
			(unlocked yes)
			(layer "F.Fab")
			(hide yes)
			(effects
				(font
					(size 1 1)
					(thickness 0.15)
				)
			)
		)
		(property "License" "Apache-2.0"
			(at 0 0 0)
			(unlocked yes)
			(layer "F.Fab")
			(hide yes)
			(effects
				(font
					(size 1 1)
					(thickness 0.15)
				)
			)
		)
		(sheetname "/USB/")
		(sheetfile "usb.kicad_sch")
		(attr exclude_from_pos_files exclude_from_bom)
		(fp_circle
			(center 0 0)
			(end 0.475 0)
			(stroke
				(width 0.05)
				(type default)
			)
			(fill no)
			(layer "F.CrtYd")
		)
		(fp_text user "Author: Antmicro"
			(at -0.4 3.901 0)
			(layer "F.Fab")
			(effects
				(font
					(size 0.7 0.7)
					(thickness 0.15)
				)
				(justify left bottom)
			)
		)
		(fp_text user "License: Apache-2.0"
			(at -0.4 5.101 0)
			(layer "F.Fab")
			(effects
				(font
					(size 0.7 0.7)
					(thickness 0.15)
				)
				(justify left bottom)
			)
		)
		(fp_text user "${REFERENCE}"
			(at -0.4 2.7 0)
			(layer "F.Fab")
			(effects
				(font
					(size 0.7 0.7)
					(thickness 0.15)
				)
				(justify left bottom)
			)
		)
		(pad "1" smd circle
			(at 0 0)
			(size 0.75 0.75)
			(layers "F.Cu" "F.Mask")
			(net 30 "/USB/USB_1V2")
			(pinfunction "1")
			(pintype "passive")
		)
	)
	(footprint "antmicro-footprints:TP_SMD_0.75mm"
		(layer "F.Cu")
		(at 88.117962 132.9165 180)
		(property "Reference" "TP914"
			(at -0.152038 4.1365 0)
			(layer "F.SilkS")
			(effects
				(font
					(size 0.7 0.7)
					(thickness 0.15)
				)
				(justify right bottom)
			)
		)
		(property "Value" "TP_0.75mm_SMD"
			(at 0 1.2 0)
			(layer "F.Fab")
			(effects
				(font
					(size 0.7 0.7)
					(thickness 0.15)
				)
				(justify right bottom)
			)
		)
		(property "MPN" ""
			(at 0 0 180)
			(unlocked yes)
			(layer "F.Fab")
			(hide yes)
			(effects
				(font
					(size 1 1)
					(thickness 0.15)
				)
			)
		)
		(property "Manufacturer" ""
			(at 0 0 180)
			(unlocked yes)
			(layer "F.Fab")
			(hide yes)
			(effects
				(font
					(size 1 1)
					(thickness 0.15)
				)
			)
		)
		(property "Author" "Antmicro"
			(at 0 0 180)
			(unlocked yes)
			(layer "F.Fab")
			(hide yes)
			(effects
				(font
					(size 1 1)
					(thickness 0.15)
				)
			)
		)
		(property "License" "Apache-2.0"
			(at 0 0 180)
			(unlocked yes)
			(layer "F.Fab")
			(hide yes)
			(effects
				(font
					(size 1 1)
					(thickness 0.15)
				)
			)
		)
		(sheetname "/USB/")
		(sheetfile "usb.kicad_sch")
		(attr exclude_from_pos_files exclude_from_bom)
		(fp_circle
			(center 0 0)
			(end 0.475 0)
			(stroke
				(width 0.05)
				(type default)
			)
			(fill no)
			(layer "F.CrtYd")
		)
		(fp_text user "License: Apache-2.0"
			(at -0.4 5.101 180)
			(layer "F.Fab")
			(effects
				(font
					(size 0.7 0.7)
					(thickness 0.15)
				)
				(justify left bottom)
			)
		)
		(fp_text user "Author: Antmicro"
			(at -0.4 3.901 180)
			(layer "F.Fab")
			(effects
				(font
					(size 0.7 0.7)
					(thickness 0.15)
				)
				(justify left bottom)
			)
		)
		(fp_text user "${REFERENCE}"
			(at -0.4 2.7 180)
			(layer "F.Fab")
			(effects
				(font
					(size 0.7 0.7)
					(thickness 0.15)
				)
				(justify left bottom)
			)
		)
		(pad "1" smd circle
			(at 0 0 180)
			(size 0.75 0.75)
			(layers "F.Cu" "F.Mask")
			(net 439 "Net-(U905-PD2_CC1)")
			(pinfunction "1")
			(pintype "passive")
		)
	)
)
